(kicad_pcb
	(version 20260206)
	(generator "pcbnew")
	(generator_version "10.0")
	(general
		(thickness 1.6)
		(legacy_teardrops no)
	)
	(paper "A4")
	(title_block
		(title "netronome-mezz — pcbd0082-001_rev01_jul9_a.brd")
		(comment 1 "Open CloudServer (Microsoft) / footprints 486-495 of 714")
	)
	(layers
		(0 "F.Cu" signal "TOP")
		(4 "In1.Cu" signal "02_GND")
		(6 "In2.Cu" signal "03_SIG")
		(8 "In3.Cu" signal "04_SIG")
		(10 "In4.Cu" signal "05_GND")
		(12 "In5.Cu" signal "06_PWR1")
		(14 "In6.Cu" signal "07_SIG")
		(16 "In7.Cu" signal "08_SIG")
		(18 "In8.Cu" signal "09_GND")
		(2 "B.Cu" signal "BOTTOM")
		(9 "F.Adhes" user "F.Adhesive")
		(11 "B.Adhes" user "B.Adhesive")
		(13 "F.Paste" user "Package Geometry/Pastemask Top")
		(15 "B.Paste" user "Package Geometry/Pastemask Bottom")
		(5 "F.SilkS" user "Ref Des/Silkscreen Top")
		(7 "B.SilkS" user "Ref Des/Silkscreen Bottom")
		(1 "F.Mask" user "Board Geometry/Soldermask Top")
		(3 "B.Mask" user "Board Geometry/Soldermask Bottom")
		(17 "Dwgs.User" user "User.Drawings")
		(19 "Cmts.User" user "User.Comments")
		(21 "Eco1.User" user "User.Eco1")
		(23 "Eco2.User" user "User.Eco2")
		(25 "Edge.Cuts" user "Board Geometry/Outline")
		(27 "Margin" user)
		(31 "F.CrtYd" user "Package Geometry/Place Bound Top")
		(29 "B.CrtYd" user "Package Geometry/Place Bound Bottom")
		(35 "F.Fab" user "Ref Des/Assembly Top")
		(33 "B.Fab" user "Ref Des/Assembly Bottom")
		(45 "User.4" user "COMPVAL_TYPE_BOTTOM")
	)
	(footprint ""
		(layer "B.Cu")
		(at 76.251003 3.499002)
		(property "Reference" "V_A-DQS0-P"
			(at 0 0 0)
			(layer "B.SilkS")
			(hide yes)
			(effects
				(font
					(size 1.27 1.27)
				)
				(justify mirror)
			)
		)
		(property "Value" ""
			(at 0 0 0)
			(layer "B.Fab")
			(effects
				(font
					(size 1.27 1.27)
				)
				(justify mirror)
			)
		)
		(duplicate_pad_numbers_are_jumpers no)
		(pad "1" thru_hole circle
			(at 0 0 180)
			(size 0.4572 0.4572)
			(drill 0.20574)
			(layers "*.Cu" "*.Mask")
			(remove_unused_layers no)
			(net "DDR0_32A_DQS0_P")
			(clearance 0.1143)
			(thermal_gap 0.1143)
		)
	)
	(footprint ""
		(layer "B.Cu")
		(at 33.274 46.736)
		(property "Reference" "TP6"
			(at -0.66167 3.175 270)
			(unlocked yes)
			(layer "B.SilkS")
			(effects
				(font
					(size 0.7874 0.5842)
					(thickness 0.127)
				)
				(justify left mirror)
			)
		)
		(property "Value" "*"
			(at 0.4826 -0.14732 0)
			(unlocked yes)
			(layer "B.Fab")
			(hide yes)
			(effects
				(font
					(size 1.27 0.9652)
					(thickness 0.000001)
				)
				(justify left mirror)
			)
		)
		(property "Device Type" "TP_SMALL"
			(at 0.4826 -0.14732 0)
			(unlocked yes)
			(layer "B.Fab")
			(hide yes)
			(effects
				(font
					(size 1.27 0.9652)
					(thickness 0.000001)
				)
				(justify left mirror)
			)
		)
		(duplicate_pad_numbers_are_jumpers no)
		(fp_line
			(start -0.8636 -0.8636)
			(end 0.8636 -0.8636)
			(stroke
				(width 0.1524)
				(type default)
			)
			(layer "B.SilkS")
		)
		(fp_line
			(start -0.8636 0.8636)
			(end -0.8636 -0.8636)
			(stroke
				(width 0.1524)
				(type default)
			)
			(layer "B.SilkS")
		)
		(fp_line
			(start 0.8636 -0.8636)
			(end 0.8636 0.8636)
			(stroke
				(width 0.1524)
				(type default)
			)
			(layer "B.SilkS")
		)
		(fp_line
			(start 0.8636 0.8636)
			(end -0.8636 0.8636)
			(stroke
				(width 0.1524)
				(type default)
			)
			(layer "B.SilkS")
		)
		(fp_poly
			(pts
				(xy 0.635 -0.635) (xy 0.635 0.635) (xy -0.635 0.635) (xy -0.635 -0.635)
			)
			(stroke
				(width 0)
				(type default)
			)
			(fill no)
			(layer "B.CrtYd")
		)
		(pad "1" smd rect
			(at 0 0 180)
			(size 1.27 1.27)
			(layers "B.Cu" "B.Mask" "B.Paste")
			(net "NFP_JTAG_ARM_TCK")
		)
	)
	(footprint ""
		(layer "B.Cu")
		(at 27.813 22.352)
		(property "Reference" "R57"
			(at -0.02667 -0.635 270)
			(unlocked yes)
			(layer "B.SilkS")
			(effects
				(font
					(size 0.7874 0.5842)
					(thickness 0.127)
				)
				(justify left mirror)
			)
		)
		(property "Value" "4.75K"
			(at 0.148158 1.3462 270)
			(unlocked yes)
			(layer "B.Fab")
			(hide yes)
			(effects
				(font
					(size 1.27 0.9652)
					(thickness 0.000001)
				)
				(justify left mirror)
			)
		)
		(property "Device Type" "REST4024"
			(at 0.148158 1.3462 270)
			(unlocked yes)
			(layer "B.Fab")
			(hide yes)
			(effects
				(font
					(size 1.27 0.9652)
					(thickness 0.000001)
				)
				(justify left mirror)
			)
		)
		(duplicate_pad_numbers_are_jumpers no)
		(fp_poly
			(pts
				(xy -0.635 1.0668) (xy -0.635 -1.0668) (xy 0.635 -1.0668) (xy 0.635 1.0668)
			)
			(stroke
				(width 0)
				(type default)
			)
			(fill no)
			(layer "B.CrtYd")
		)
		(fp_line
			(start -0.254 -0.508)
			(end -0.254 0.508)
			(stroke
				(width 0.0254)
				(type default)
			)
			(layer "B.Fab")
		)
		(fp_line
			(start -0.254 0.508)
			(end 0.254 0.508)
			(stroke
				(width 0.0254)
				(type default)
			)
			(layer "B.Fab")
		)
		(fp_line
			(start 0.254 -0.508)
			(end -0.254 -0.508)
			(stroke
				(width 0.0254)
				(type default)
			)
			(layer "B.Fab")
		)
		(fp_line
			(start 0.254 0.508)
			(end 0.254 -0.508)
			(stroke
				(width 0.0254)
				(type default)
			)
			(layer "B.Fab")
		)
		(pad "1" smd rect
			(at 0 -0.4191 180)
			(size 0.508 0.5334)
			(layers "B.Cu" "B.Mask" "B.Paste")
			(net "NFP_SRESET_L")
		)
		(pad "2" smd rect
			(at 0 0.4191 180)
			(size 0.508 0.5334)
			(layers "B.Cu" "B.Mask" "B.Paste")
			(net "GND")
		)
		(zone
			(layer "B.Cu")
			(hatch none 0.5)
			(connect_pads
				(clearance 0)
			)
			(min_thickness 0.25)
			(keepout
				(tracks not_allowed)
				(vias allowed)
				(pads allowed)
				(copperpour not_allowed)
				(footprints allowed)
			)
			(placement
				(enabled no)
				(sheetname "")
			)
			(fill
				(thermal_gap 0.5)
				(thermal_bridge_width 0.5)
				(island_removal_mode 0)
			)
			(polygon
				(pts
					(xy 27.7876 22.3266) (xy 27.7876 22.3774) (xy 27.8384 22.3774) (xy 27.8384 22.3266)
				)
			)
		)
	)
	(footprint ""
		(layer "B.Cu")
		(at 43.737022 23.041991 90)
		(property "Reference" "C26"
			(at -0.479679 2.363978 0)
			(unlocked yes)
			(layer "B.SilkS")
			(effects
				(font
					(size 0.7874 0.5842)
					(thickness 0.127)
				)
				(justify mirror)
			)
		)
		(property "Value" ""
			(at 0 0 90)
			(layer "B.Fab")
			(effects
				(font
					(size 1.27 1.27)
				)
				(justify mirror)
			)
		)
		(duplicate_pad_numbers_are_jumpers no)
		(fp_circle
			(center 0 0)
			(end 0 0.104648)
			(stroke
				(width 0.1016)
				(type default)
			)
			(fill no)
			(layer "B.SilkS")
		)
		(fp_poly
			(pts
				(xy 0.381 -0.889) (xy 0.381 0.889) (xy -0.381 0.889) (xy -0.381 -0.889)
			)
			(stroke
				(width 0)
				(type default)
			)
			(fill no)
			(layer "B.CrtYd")
		)
		(fp_line
			(start 0.508 -1.016)
			(end 0.254 -1.016)
			(stroke
				(width 0.0254)
				(type default)
			)
			(layer "B.Fab")
		)
		(fp_line
			(start 0.254 -1.016)
			(end -0.508 -1.016)
			(stroke
				(width 0.0254)
				(type default)
			)
			(layer "B.Fab")
		)
		(fp_line
			(start -0.508 -1.016)
			(end -0.508 1.016)
			(stroke
				(width 0.0254)
				(type default)
			)
			(layer "B.Fab")
		)
		(fp_line
			(start 0.508 1.016)
			(end 0.508 -1.016)
			(stroke
				(width 0.0254)
				(type default)
			)
			(layer "B.Fab")
		)
		(fp_line
			(start -0.508 1.016)
			(end 0.508 1.016)
			(stroke
				(width 0.0254)
				(type default)
			)
			(layer "B.Fab")
		)
		(pad "1" smd custom
			(at 0 -0.500126 270)
			(size 0.127 0.127)
			(layers "B.Cu" "B.Mask" "B.Paste")
			(net "VDDA_PLL")
			(options
				(clearance outline)
				(anchor circle)
			)
			(primitives
				(gr_poly
					(pts
						(xy -0.1778 0.254) (xy 0.1778 0.254) (xy 0.254 0.1778) (xy 0.254 -0.1778) (xy 0.1778 -0.254) (xy -0.1778 -0.254)
						(xy -0.254 -0.1778) (xy -0.254 0.1778)
					)
					(width 0)
					(fill yes)
				)
			)
		)
		(pad "2" smd custom
			(at 0 0.500126 270)
			(size 0.127 0.127)
			(layers "B.Cu" "B.Mask" "B.Paste")
			(net "GND")
			(options
				(clearance outline)
				(anchor circle)
			)
			(primitives
				(gr_poly
					(pts
						(xy -0.1778 0.254) (xy 0.1778 0.254) (xy 0.254 0.1778) (xy 0.254 -0.1778) (xy 0.1778 -0.254) (xy -0.1778 -0.254)
						(xy -0.254 -0.1778) (xy -0.254 0.1778)
					)
					(width 0)
					(fill yes)
				)
			)
		)
	)
	(footprint ""
		(layer "B.Cu")
		(at 76.251003 26.613002)
		(property "Reference" "V_A-DQS4-P"
			(at 0 0 0)
			(layer "B.SilkS")
			(hide yes)
			(effects
				(font
					(size 1.27 1.27)
				)
				(justify mirror)
			)
		)
		(property "Value" ""
			(at 0 0 0)
			(layer "B.Fab")
			(effects
				(font
					(size 1.27 1.27)
				)
				(justify mirror)
			)
		)
		(duplicate_pad_numbers_are_jumpers no)
		(pad "1" thru_hole circle
			(at 0 0 180)
			(size 0.4572 0.4572)
			(drill 0.20574)
			(layers "*.Cu" "*.Mask")
			(remove_unused_layers no)
			(net "DDR0_32A_DQS4_P")
			(clearance 0.1143)
			(thermal_gap 0.1143)
		)
	)
	(footprint ""
		(layer "B.Cu")
		(at 43.5229 36.957 180)
		(property "Reference" "R76"
			(at -0.01143 0.889 270)
			(unlocked yes)
			(layer "B.SilkS")
			(effects
				(font
					(size 0.7874 0.5842)
					(thickness 0.127)
				)
				(justify left mirror)
			)
		)
		(property "Value" "4.75K"
			(at 0.148158 1.3462 90)
			(unlocked yes)
			(layer "B.Fab")
			(hide yes)
			(effects
				(font
					(size 1.27 0.9652)
					(thickness 0.000001)
				)
				(justify left mirror)
			)
		)
		(property "Device Type" "REST4024"
			(at 0.148158 1.3462 90)
			(unlocked yes)
			(layer "B.Fab")
			(hide yes)
			(effects
				(font
					(size 1.27 0.9652)
					(thickness 0.000001)
				)
				(justify left mirror)
			)
		)
		(duplicate_pad_numbers_are_jumpers no)
		(fp_poly
			(pts
				(xy -0.635 1.0668) (xy -0.635 -1.0668) (xy 0.635 -1.0668) (xy 0.635 1.0668)
			)
			(stroke
				(width 0)
				(type default)
			)
			(fill no)
			(layer "B.CrtYd")
		)
		(fp_line
			(start 0.254 0.508)
			(end 0.254 -0.508)
			(stroke
				(width 0.0254)
				(type default)
			)
			(layer "B.Fab")
		)
		(fp_line
			(start 0.254 -0.508)
			(end -0.254 -0.508)
			(stroke
				(width 0.0254)
				(type default)
			)
			(layer "B.Fab")
		)
		(fp_line
			(start -0.254 0.508)
			(end 0.254 0.508)
			(stroke
				(width 0.0254)
				(type default)
			)
			(layer "B.Fab")
		)
		(fp_line
			(start -0.254 -0.508)
			(end -0.254 0.508)
			(stroke
				(width 0.0254)
				(type default)
			)
			(layer "B.Fab")
		)
		(pad "1" smd rect
			(at 0 -0.4191)
			(size 0.508 0.5334)
			(layers "B.Cu" "B.Mask" "B.Paste")
			(net "CORE_FB_PH2_THERM_L")
		)
		(pad "2" smd rect
			(at 0 0.4191)
			(size 0.508 0.5334)
			(layers "B.Cu" "B.Mask" "B.Paste")
			(net "VDD_3.3V")
		)
		(zone
			(layer "B.Cu")
			(hatch none 0.5)
			(connect_pads
				(clearance 0)
			)
			(min_thickness 0.25)
			(keepout
				(tracks not_allowed)
				(vias allowed)
				(pads allowed)
				(copperpour not_allowed)
				(footprints allowed)
			)
			(placement
				(enabled no)
				(sheetname "")
			)
			(fill
				(thermal_gap 0.5)
				(thermal_bridge_width 0.5)
				(island_removal_mode 0)
			)
			(polygon
				(pts
					(xy 43.5483 36.9824) (xy 43.5483 36.9316) (xy 43.4975 36.9316) (xy 43.4975 36.9824)
				)
			)
		)
	)
	(footprint ""
		(layer "B.Cu")
		(at 52.237005 33.54197)
		(property "Reference" "C173"
			(at 0 0 0)
			(layer "B.SilkS")
			(hide yes)
			(effects
				(font
					(size 1.27 1.27)
				)
				(justify mirror)
			)
		)
		(property "Value" ""
			(at 0 0 0)
			(layer "B.Fab")
			(effects
				(font
					(size 1.27 1.27)
				)
				(justify mirror)
			)
		)
		(duplicate_pad_numbers_are_jumpers no)
		(fp_circle
			(center 0 0)
			(end 0.104648 0)
			(stroke
				(width 0.1016)
				(type default)
			)
			(fill no)
			(layer "B.SilkS")
		)
		(fp_poly
			(pts
				(xy 0.381 -0.889) (xy 0.381 0.889) (xy -0.381 0.889) (xy -0.381 -0.889)
			)
			(stroke
				(width 0)
				(type default)
			)
			(fill no)
			(layer "B.CrtYd")
		)
		(fp_line
			(start -0.508 -1.016)
			(end -0.508 1.016)
			(stroke
				(width 0.0254)
				(type default)
			)
			(layer "B.Fab")
		)
		(fp_line
			(start -0.508 1.016)
			(end 0.508 1.016)
			(stroke
				(width 0.0254)
				(type default)
			)
			(layer "B.Fab")
		)
		(fp_line
			(start 0.254 -1.016)
			(end -0.508 -1.016)
			(stroke
				(width 0.0254)
				(type default)
			)
			(layer "B.Fab")
		)
		(fp_line
			(start 0.508 -1.016)
			(end 0.254 -1.016)
			(stroke
				(width 0.0254)
				(type default)
			)
			(layer "B.Fab")
		)
		(fp_line
			(start 0.508 1.016)
			(end 0.508 -1.016)
			(stroke
				(width 0.0254)
				(type default)
			)
			(layer "B.Fab")
		)
		(pad "1" smd custom
			(at 0 -0.500126 180)
			(size 0.127 0.127)
			(layers "B.Cu" "B.Mask" "B.Paste")
			(net "VDD_CORE")
			(options
				(clearance outline)
				(anchor circle)
			)
			(primitives
				(gr_poly
					(pts
						(xy -0.1778 0.254) (xy 0.1778 0.254) (xy 0.254 0.1778) (xy 0.254 -0.1778) (xy 0.1778 -0.254) (xy -0.1778 -0.254)
						(xy -0.254 -0.1778) (xy -0.254 0.1778)
					)
					(width 0)
					(fill yes)
				)
			)
		)
		(pad "2" smd custom
			(at 0 0.500126 180)
			(size 0.127 0.127)
			(layers "B.Cu" "B.Mask" "B.Paste")
			(net "GND")
			(options
				(clearance outline)
				(anchor circle)
			)
			(primitives
				(gr_poly
					(pts
						(xy -0.1778 0.254) (xy 0.1778 0.254) (xy 0.254 0.1778) (xy 0.254 -0.1778) (xy 0.1778 -0.254) (xy -0.1778 -0.254)
						(xy -0.254 -0.1778) (xy -0.254 0.1778)
					)
					(width 0)
					(fill yes)
				)
			)
		)
	)
	(footprint ""
		(layer "B.Cu")
		(at 59.236991 11.542014)
		(property "Reference" "C166"
			(at -0.970661 -0.112014 270)
			(unlocked yes)
			(layer "B.SilkS")
			(effects
				(font
					(size 0.7874 0.5842)
					(thickness 0.127)
				)
				(justify mirror)
			)
		)
		(property "Value" ""
			(at 0 0 0)
			(layer "B.Fab")
			(effects
				(font
					(size 1.27 1.27)
				)
				(justify mirror)
			)
		)
		(duplicate_pad_numbers_are_jumpers no)
		(fp_circle
			(center 0 0)
			(end 0.104648 0)
			(stroke
				(width 0.1016)
				(type default)
			)
			(fill no)
			(layer "B.SilkS")
		)
		(fp_poly
			(pts
				(xy 0.381 -0.889) (xy 0.381 0.889) (xy -0.381 0.889) (xy -0.381 -0.889)
			)
			(stroke
				(width 0)
				(type default)
			)
			(fill no)
			(layer "B.CrtYd")
		)
		(fp_line
			(start -0.508 -1.016)
			(end -0.508 1.016)
			(stroke
				(width 0.0254)
				(type default)
			)
			(layer "B.Fab")
		)
		(fp_line
			(start -0.508 1.016)
			(end 0.508 1.016)
			(stroke
				(width 0.0254)
				(type default)
			)
			(layer "B.Fab")
		)
		(fp_line
			(start 0.254 -1.016)
			(end -0.508 -1.016)
			(stroke
				(width 0.0254)
				(type default)
			)
			(layer "B.Fab")
		)
		(fp_line
			(start 0.508 -1.016)
			(end 0.254 -1.016)
			(stroke
				(width 0.0254)
				(type default)
			)
			(layer "B.Fab")
		)
		(fp_line
			(start 0.508 1.016)
			(end 0.508 -1.016)
			(stroke
				(width 0.0254)
				(type default)
			)
			(layer "B.Fab")
		)
		(pad "1" smd custom
			(at 0 -0.500126 180)
			(size 0.127 0.127)
			(layers "B.Cu" "B.Mask" "B.Paste")
			(net "VDD_CORE")
			(options
				(clearance outline)
				(anchor circle)
			)
			(primitives
				(gr_poly
					(pts
						(xy -0.1778 0.254) (xy 0.1778 0.254) (xy 0.254 0.1778) (xy 0.254 -0.1778) (xy 0.1778 -0.254) (xy -0.1778 -0.254)
						(xy -0.254 -0.1778) (xy -0.254 0.1778)
					)
					(width 0)
					(fill yes)
				)
			)
		)
		(pad "2" smd custom
			(at 0 0.500126 180)
			(size 0.127 0.127)
			(layers "B.Cu" "B.Mask" "B.Paste")
			(net "GND")
			(options
				(clearance outline)
				(anchor circle)
			)
			(primitives
				(gr_poly
					(pts
						(xy -0.1778 0.254) (xy 0.1778 0.254) (xy 0.254 0.1778) (xy 0.254 -0.1778) (xy 0.1778 -0.254) (xy -0.1778 -0.254)
						(xy -0.254 -0.1778) (xy -0.254 0.1778)
					)
					(width 0)
					(fill yes)
				)
			)
		)
	)
	(footprint ""
		(layer "B.Cu")
		(at 64.897 35.687)
		(property "Reference" "R126"
			(at 0 0 0)
			(layer "B.SilkS")
			(hide yes)
			(effects
				(font
					(size 1.27 1.27)
				)
				(justify mirror)
			)
		)
		(property "Value" "10K"
			(at 0.148158 1.3462 270)
			(unlocked yes)
			(layer "B.Fab")
			(hide yes)
			(effects
				(font
					(size 1.27 0.9652)
					(thickness 0.000001)
				)
				(justify left mirror)
			)
		)
		(property "Device Type" "REST0005"
			(at 0.148158 1.3462 270)
			(unlocked yes)
			(layer "B.Fab")
			(hide yes)
			(effects
				(font
					(size 1.27 0.9652)
					(thickness 0.000001)
				)
				(justify left mirror)
			)
		)
		(duplicate_pad_numbers_are_jumpers no)
		(fp_poly
			(pts
				(xy -0.635 1.0668) (xy -0.635 -1.0668) (xy 0.635 -1.0668) (xy 0.635 1.0668)
			)
			(stroke
				(width 0)
				(type default)
			)
			(fill no)
			(layer "B.CrtYd")
		)
		(fp_line
			(start -0.254 -0.508)
			(end -0.254 0.508)
			(stroke
				(width 0.0254)
				(type default)
			)
			(layer "B.Fab")
		)
		(fp_line
			(start -0.254 0.508)
			(end 0.254 0.508)
			(stroke
				(width 0.0254)
				(type default)
			)
			(layer "B.Fab")
		)
		(fp_line
			(start 0.254 -0.508)
			(end -0.254 -0.508)
			(stroke
				(width 0.0254)
				(type default)
			)
			(layer "B.Fab")
		)
		(fp_line
			(start 0.254 0.508)
			(end 0.254 -0.508)
			(stroke
				(width 0.0254)
				(type default)
			)
			(layer "B.Fab")
		)
		(pad "1" smd rect
			(at 0 -0.4191 180)
			(size 0.508 0.5334)
			(layers "B.Cu" "B.Mask" "B.Paste")
			(net "VDD_5.0V")
		)
		(pad "2" smd rect
			(at 0 0.4191 180)
			(size 0.508 0.5334)
			(layers "B.Cu" "B.Mask" "B.Paste")
			(net "10N2253")
		)
		(zone
			(layer "B.Cu")
			(hatch none 0.5)
			(connect_pads
				(clearance 0)
			)
			(min_thickness 0.25)
			(keepout
				(tracks not_allowed)
				(vias allowed)
				(pads allowed)
				(copperpour not_allowed)
				(footprints allowed)
			)
			(placement
				(enabled no)
				(sheetname "")
			)
			(fill
				(thermal_gap 0.5)
				(thermal_bridge_width 0.5)
				(island_removal_mode 0)
			)
			(polygon
				(pts
					(xy 64.8716 35.6616) (xy 64.8716 35.7124) (xy 64.9224 35.7124) (xy 64.9224 35.6616)
				)
			)
		)
	)
	(footprint ""
		(layer "B.Cu")
		(at 72.251011 2.699004)
		(property "Reference" "V_A-DQ12"
			(at 0 0 0)
			(layer "B.SilkS")
			(hide yes)
			(effects
				(font
					(size 1.27 1.27)
				)
				(justify mirror)
			)
		)
		(property "Value" ""
			(at 0 0 0)
			(layer "B.Fab")
			(effects
				(font
					(size 1.27 1.27)
				)
				(justify mirror)
			)
		)
		(duplicate_pad_numbers_are_jumpers no)
		(pad "1" thru_hole circle
			(at 0 0 180)
			(size 0.4572 0.4572)
			(drill 0.20574)
			(layers "*.Cu" "*.Mask")
			(remove_unused_layers no)
			(net "DDR0_32A_DQ12")
			(clearance 0.1143)
			(thermal_gap 0.1143)
		)
	)
)
